(kicad_pcb
	(version 20221018)
	(generator pcbnew)
	(general
    (thickness 1.586)
  )
	(paper "A4")
	(title_block
    (date "2024-03-26")
    (rev "1.1.3")
		(comment 9 "footprints 52-60 of 146")
	)
	(layers
    (0 "F.Cu" signal)
    (1 "In1.Cu" power)
    (2 "In2.Cu" power)
    (31 "B.Cu" signal)
    (32 "B.Adhes" user "B.Adhesive")
    (33 "F.Adhes" user "F.Adhesive")
    (34 "B.Paste" user)
    (35 "F.Paste" user)
    (36 "B.SilkS" user "B.Silkscreen")
    (37 "F.SilkS" user "F.Silkscreen")
    (38 "B.Mask" user)
    (39 "F.Mask" user)
    (40 "Dwgs.User" user "User.Drawings")
    (41 "Cmts.User" user "User.Comments")
    (42 "Eco1.User" user "User.Eco1")
    (43 "Eco2.User" user "User.Eco2")
    (44 "Edge.Cuts" user)
    (45 "Margin" user)
    (46 "B.CrtYd" user "B.Courtyard")
    (47 "F.CrtYd" user "F.Courtyard")
    (48 "B.Fab" user)
    (49 "F.Fab" user)
  )
	(footprint "scalenode-cm4-baseboard-footprints:R_0402_1005Metric" (layer "F.Cu")
    (at 89.8 95.6 -90)
    (descr "Resistor SMD 0402")
    (tags "resistor SMD 0402")
    (property "Author" "Antmicro")
    (property "DNP" "DNP")
    (property "License" "Apache-2.0")
    (property "MPN" "CR0402-FX-63R4GLF")
    (property "Manufacturer" "Bourns")
    (property "Sheetfile" "poe.kicad_sch")
    (property "Sheetname" "PoE")
    (property "Tolerance" "1%")
    (property "Val" "63R4")
    (property "dnp" "")
    (property "exclude_from_bom" "")
    (property "ki_description" "63R4 resistor in 0402 package with 1% tolerance")
    (attr exclude_from_pos_files exclude_from_bom)
    (fp_text reference "R35" (at 1.1 0.65 -90) (layer "F.SilkS")
        (effects (font (size 0.7 0.7) (thickness 0.15)) (justify left bottom))
    )
    (fp_text value "R_63R4_0402" (at 0 1.4 -90) (layer "F.Fab")
        (effects (font (size 0.7 0.7) (thickness 0.15)) (justify left bottom))
    )
    (fp_text user "${REFERENCE}" (at -0.95 3.168 -90) (layer "F.Fab") hide
        (effects (font (size 0.7 0.7) (thickness 0.15)) (justify left bottom))
    )
    (fp_text user "License: Apache-2.0" (at -0.95 5.169 -90) (layer "F.Fab") hide
        (effects (font (size 0.7 0.7) (thickness 0.15)) (justify left bottom))
    )
    (fp_text user "Author: Antmicro" (at -0.95 4.169 -90) (layer "F.Fab") hide
        (effects (font (size 0.7 0.7) (thickness 0.15)) (justify left bottom))
    )
    (fp_rect (start -0.95 -0.48) (end 0.95 0.48)
      (stroke (width 0.05) (type solid)) (fill none) (layer "F.CrtYd"))
    (fp_rect (start -0.5 -0.25) (end 0.5 0.25)
      (stroke (width 0.15) (type solid)) (fill none) (layer "F.Fab"))
    (pad "1" smd roundrect (at -0.485 0 270) (size 0.59 0.64) (layers "F.Cu" "F.Paste" "F.Mask") (roundrect_rratio 0.25)
      (net 257 "Net-(U3-CLSB)") (pintype "passive"))
    (pad "2" smd roundrect (at 0.485 0 270) (size 0.59 0.64) (layers "F.Cu" "F.Paste" "F.Mask") (roundrect_rratio 0.25)
      (net 5 "VSS") (pintype "passive"))
  )
	(footprint "scalenode-cm4-baseboard-footprints:Ethernet_Jack_SS-74800-144" (layer "F.Cu")
    (at 88.923 71.45 90)
    (descr "https://www.belfuse.com/resources/drawings/stewartconnector/dr-STW-SS-74800-144.pdf")
    (property "Author" "Antmicro")
    (property "License" "Apache-2.0")
    (property "MPN" "SS-74800-144")
    (property "Manufacturer" "Bel")
    (property "Sheetfile" "poe.kicad_sch")
    (property "Sheetname" "PoE")
    (property "ki_description" "Jack Modular Connector 8p8c (RJ45, Ethernet) 90° Angle (Right) Shielded, EMI Finger Cat5e")
    (property "ki_keywords" "CONNECTOR")
    (attr through_hole)
    (fp_text reference "J6" (at -6.3 -2.423 180) (layer "F.SilkS")
        (effects (font (size 0.7 0.7) (thickness 0.15)) (justify right bottom))
    )
    (fp_text value "SS-74800-144" (at 0 -14.6 90) (layer "F.Fab")
        (effects (font (size 0.7 0.7) (thickness 0.15)) (justify right bottom))
    )
    (fp_text user "License: Apache-2.0" (at -12.471 18.341 90) (layer "F.Fab") hide
        (effects (font (size 0.7 0.7) (thickness 0.15)) (justify left bottom))
    )
    (fp_text user "${REFERENCE}" (at -12.471 15.941 90) (layer "F.Fab") hide
        (effects (font (size 0.7 0.7) (thickness 0.15)) (justify left bottom))
    )
    (fp_text user "Author: Antmicro" (at -12.471 17.141 90) (layer "F.Fab") hide
        (effects (font (size 0.7 0.7) (thickness 0.15)) (justify left bottom))
    )
    (fp_circle (center 0 6.85) (end -0.05 6.85)
      (stroke (width 0.15) (type solid)) (fill solid) (layer "F.SilkS"))
    (fp_line (start -5.4356 -13.9446) (end -5.4356 6.731)
      (stroke (width 0.05) (type solid)) (layer "F.CrtYd"))
    (fp_line (start -5.4356 -13.9446) (end 12.5476 -13.9446)
      (stroke (width 0.05) (type solid)) (layer "F.CrtYd"))
    (fp_line (start 12.5476 -13.9446) (end 12.5476 6.731)
      (stroke (width 0.05) (type solid)) (layer "F.CrtYd"))
    (fp_line (start 12.5476 6.731) (end -5.4356 6.731)
      (stroke (width 0.05) (type solid)) (layer "F.CrtYd"))
    (pad "1" thru_hole circle (at 0 0 270) (size 1.524 1.524) (drill 0.89) (layers "*.Cu" "*.Mask")
      (net 153 "/PoE/T_ETH_D0_P") (pintype "passive"))
    (pad "2" thru_hole circle (at 1.016 1.778 270) (size 1.524 1.524) (drill 0.89) (layers "*.Cu" "*.Mask")
      (net 154 "/PoE/T_ETH_D0_N") (pintype "passive"))
    (pad "3" thru_hole circle (at 2.032 0 270) (size 1.524 1.524) (drill 0.89) (layers "*.Cu" "*.Mask")
      (net 155 "/PoE/T_ETH_D1_P") (pintype "passive"))
    (pad "4" thru_hole circle (at 3.048 1.778 270) (size 1.524 1.524) (drill 0.89) (layers "*.Cu" "*.Mask")
      (net 156 "/PoE/T_ETH_D2_P") (pintype "passive"))
    (pad "5" thru_hole circle (at 4.064 0 270) (size 1.524 1.524) (drill 0.89) (layers "*.Cu" "*.Mask")
      (net 157 "/PoE/T_ETH_D2_N") (pintype "passive"))
    (pad "6" thru_hole circle (at 5.08 1.778 270) (size 1.524 1.524) (drill 0.89) (layers "*.Cu" "*.Mask")
      (net 158 "/PoE/T_ETH_D1_N") (pintype "passive"))
    (pad "7" thru_hole circle (at 6.096 0 270) (size 1.524 1.524) (drill 0.89) (layers "*.Cu" "*.Mask")
      (net 159 "/PoE/T_ETH_D3_P") (pintype "passive"))
    (pad "8" thru_hole circle (at 7.112 1.778 270) (size 1.524 1.524) (drill 0.89) (layers "*.Cu" "*.Mask")
      (net 160 "/PoE/T_ETH_D3_N") (pintype "passive"))
    (pad "9" thru_hole circle (at -2.9718 4.1402 270) (size 1.7 1.7) (drill 1) (layers "*.Cu" "*.Mask")
      (net 86 "ETH_LEDY") (pinfunction "9") (pintype "passive"))
    (pad "10" thru_hole circle (at -0.6858 4.1402 270) (size 1.7 1.7) (drill 1) (layers "*.Cu" "*.Mask")
      (net 225 "Net-(J6-Pad10)") (pinfunction "10") (pintype "passive"))
    (pad "11" thru_hole circle (at 7.7978 4.1402 270) (size 1.7 1.7) (drill 1) (layers "*.Cu" "*.Mask")
      (net 84 "ETH_LEDG") (pinfunction "11") (pintype "passive"))
    (pad "12" thru_hole circle (at 10.0838 4.1402 270) (size 1.7 1.7) (drill 1) (layers "*.Cu" "*.Mask")
      (net 226 "Net-(J6-Pad12)") (pinfunction "12") (pintype "passive"))
    (pad "SH" thru_hole oval (at -6.3627 -6.2738 270) (size 1.6 3) (drill oval 0.89 2.39) (layers "*.Cu" "*.Mask")
      (net 230 "Earth") (pinfunction "SHIELD") (pintype "passive"))
    (pad "SH" thru_hole oval (at 13.4747 -6.2738 270) (size 1.6 3) (drill oval 0.89 2.39) (layers "*.Cu" "*.Mask")
      (net 230 "Earth") (pinfunction "SHIELD") (pintype "passive"))
  )
	(footprint "scalenode-cm4-baseboard-footprints:TP_SMD_1mm" (layer "F.Cu")
    (at 123.2858 68.8842)
    (property "Author" "Antmicro")
    (property "License" "Apache-2.0")
    (property "MPN" "")
    (property "Manufacturer" "")
    (property "Sheetfile" "poe.kicad_sch")
    (property "Sheetname" "PoE")
    (property "ki_description" "Test Point 1mm")
    (attr exclude_from_pos_files)
    (fp_text reference "TP4" (at 0 -0.731898) (layer "F.SilkS") hide
        (effects (font (size 0.7 0.7) (thickness 0.15)) (justify left bottom))
    )
    (fp_text value "TP_1mm_SMD" (at 0 1.4) (layer "F.Fab")
        (effects (font (size 0.7 0.7) (thickness 0.15)) (justify left bottom))
    )
    (fp_text user "${REFERENCE}" (at -0.5 2.8) (layer "F.Fab") hide
        (effects (font (size 0.7 0.7) (thickness 0.15)) (justify left bottom))
    )
    (fp_text user "Author: Antmicro" (at -0.5 4) (layer "F.Fab") hide
        (effects (font (size 0.7 0.7) (thickness 0.15)) (justify left bottom))
    )
    (fp_text user "License: Apache-2.0" (at -0.5 5.2) (layer "F.Fab") hide
        (effects (font (size 0.7 0.7) (thickness 0.15)) (justify left bottom))
    )
    (pad "1" smd circle (at 0 0) (size 1 1) (layers "F.Cu" "F.Mask")
      (net 11 "GND") (pinfunction "1") (pintype "passive"))
  )
	(footprint "scalenode-cm4-baseboard-footprints:R_0402_1005Metric" (layer "F.Cu")
    (at 91.3 95.1)
    (descr "Resistor SMD 0402")
    (tags "resistor SMD 0402")
    (property "Author" "Antmicro")
    (property "DNP" "DNP")
    (property "License" "Apache-2.0")
    (property "MPN" "CR0402-FX-4992GLF")
    (property "Manufacturer" "Bourns")
    (property "Sheetfile" "poe.kicad_sch")
    (property "Sheetname" "PoE")
    (property "Tolerance" "1%")
    (property "Val" "49k9")
    (property "dnp" "")
    (property "exclude_from_bom" "")
    (property "ki_description" "49k9 resistor in 0402 package with 1% tolerance")
    (attr exclude_from_pos_files exclude_from_bom)
    (fp_text reference "R38" (at -1.05 1.375) (layer "F.SilkS")
        (effects (font (size 0.7 0.7) (thickness 0.15)) (justify left bottom))
    )
    (fp_text value "R_49k9_0402" (at 0 1.4) (layer "F.Fab")
        (effects (font (size 0.7 0.7) (thickness 0.15)) (justify left bottom))
    )
    (fp_text user "${REFERENCE}" (at -0.95 3.168) (layer "F.Fab") hide
        (effects (font (size 0.7 0.7) (thickness 0.15)) (justify left bottom))
    )
    (fp_text user "License: Apache-2.0" (at -0.95 5.169) (layer "F.Fab") hide
        (effects (font (size 0.7 0.7) (thickness 0.15)) (justify left bottom))
    )
    (fp_text user "Author: Antmicro" (at -0.95 4.169) (layer "F.Fab") hide
        (effects (font (size 0.7 0.7) (thickness 0.15)) (justify left bottom))
    )
    (fp_rect (start -0.95 -0.48) (end 0.95 0.48)
      (stroke (width 0.05) (type solid)) (fill none) (layer "F.CrtYd"))
    (fp_rect (start -0.5 -0.25) (end 0.5 0.25)
      (stroke (width 0.15) (type solid)) (fill none) (layer "F.Fab"))
    (pad "1" smd roundrect (at -0.485 0) (size 0.59 0.64) (layers "F.Cu" "F.Paste" "F.Mask") (roundrect_rratio 0.25)
      (net 5 "VSS") (pintype "passive"))
    (pad "2" smd roundrect (at 0.485 0) (size 0.59 0.64) (layers "F.Cu" "F.Paste" "F.Mask") (roundrect_rratio 0.25)
      (net 260 "Net-(U3-REF)") (pintype "passive"))
  )
	(footprint "scalenode-cm4-baseboard-footprints:TP_SMD_1mm" (layer "F.Cu")
    (at 128.2858 68.8842)
    (property "Author" "Antmicro")
    (property "License" "Apache-2.0")
    (property "MPN" "")
    (property "Manufacturer" "")
    (property "Sheetfile" "compute-module.kicad_sch")
    (property "Sheetname" "Compute module")
    (property "ki_description" "Test Point 1mm")
    (attr exclude_from_pos_files)
    (fp_text reference "TP6" (at 0 -0.731898) (layer "F.SilkS") hide
        (effects (font (size 0.7 0.7) (thickness 0.15)) (justify left bottom))
    )
    (fp_text value "TP_1mm_SMD" (at 0 1.4) (layer "F.Fab")
        (effects (font (size 0.7 0.7) (thickness 0.15)) (justify left bottom))
    )
    (fp_text user "License: Apache-2.0" (at -0.5 5.2) (layer "F.Fab") hide
        (effects (font (size 0.7 0.7) (thickness 0.15)) (justify left bottom))
    )
    (fp_text user "${REFERENCE}" (at -0.5 2.8) (layer "F.Fab") hide
        (effects (font (size 0.7 0.7) (thickness 0.15)) (justify left bottom))
    )
    (fp_text user "Author: Antmicro" (at -0.5 4) (layer "F.Fab") hide
        (effects (font (size 0.7 0.7) (thickness 0.15)) (justify left bottom))
    )
    (pad "1" smd circle (at 0 0) (size 1 1) (layers "F.Cu" "F.Mask")
      (net 232 "3V3_RPi") (pinfunction "1") (pintype "passive"))
  )
	(footprint "scalenode-cm4-baseboard-footprints:Compute-Module-4_H1.5mm" locked (layer "F.Cu")
    (at 164 56.125)
    (property "Author" "Antmicro")
    (property "License" "Apache-2.0")
    (property "MPN" "SC0294")
    (property "Manufacturer" "Raspberry Pi")
    (property "Sheetfile" "compute-module.kicad_sch")
    (property "Sheetname" "Compute module")
    (property "ki_keywords" "rpi raspberry pi cm4 compute module 4 ")
    (attr through_hole exclude_from_pos_files exclude_from_bom)
    (fp_text reference "M1" (at -23.125 39.925) (layer "F.SilkS")
        (effects (font (size 0.7 0.7) (thickness 0.15)) (justify left bottom))
    )
    (fp_text value "Compute-Module-4_H1.5mm" (at 0 -0.5) (layer "F.Fab")
        (effects (font (size 0.7 0.7) (thickness 0.15)) (justify left bottom))
    )
    (fp_text user "1" (at 14.599 35.6) (layer "F.SilkS")
        (effects (font (size 0.7 0.7) (thickness 0.15)) (justify left bottom))
    )
    (fp_text user "99" (at -8.5 1.699) (layer "F.SilkS")
        (effects (font (size 0.7 0.7) (thickness 0.15)) (justify left bottom))
    )
    (fp_text user "100" (at -8.5 5.7) (layer "F.SilkS")
        (effects (font (size 0.7 0.7) (thickness 0.15)) (justify left bottom))
    )
    (fp_text user "1" (at 14.499 1.6) (layer "F.SilkS")
        (effects (font (size 0.7 0.7) (thickness 0.15)) (justify left bottom))
    )
    (fp_text user "2" (at 14.599 39.6) (layer "F.SilkS")
        (effects (font (size 0.7 0.7) (thickness 0.15)) (justify left bottom))
    )
    (fp_text user "100" (at -8.401 39.7) (layer "F.SilkS")
        (effects (font (size 0.7 0.7) (thickness 0.15)) (justify left bottom))
    )
    (fp_text user "2" (at 14.499 5.599) (layer "F.SilkS")
        (effects (font (size 0.7 0.7) (thickness 0.15)) (justify left bottom))
    )
    (fp_text user "99" (at -8.401 35.7) (layer "F.SilkS")
        (effects (font (size 0.7 0.7) (thickness 0.15)) (justify left bottom))
    )
    (fp_text user "License: Apache-2.0" (at -22 44.97) (layer "F.Fab") hide
        (effects (font (size 0.7 0.7) (thickness 0.15)) (justify left bottom))
    )
    (fp_text user "${REFERENCE}" (at -22 42.569) (layer "F.Fab") hide
        (effects (font (size 0.7 0.7) (thickness 0.15)) (justify left bottom))
    )
    (fp_text user "Author: Antmicro" (at -22 43.77) (layer "F.Fab") hide
        (effects (font (size 0.7 0.7) (thickness 0.15)) (justify left bottom))
    )
    (fp_line (start -21.93 37.569) (end -21.93 3.569)
      (stroke (width 0.15) (type solid)) (layer "F.SilkS"))
    (fp_line (start -21.93 37.569) (end -21.93 3.569)
      (stroke (width 0.15) (type solid)) (layer "F.SilkS"))
    (fp_line (start -18.93 0.569) (end 30.07 0.569)
      (stroke (width 0.15) (type solid)) (layer "F.SilkS"))
    (fp_line (start -18.93 0.57) (end 30.07 0.569)
      (stroke (width 0.15) (type solid)) (layer "F.SilkS"))
    (fp_line (start 30.07 40.569) (end -18.93 40.569)
      (stroke (width 0.15) (type solid)) (layer "F.SilkS"))
    (fp_line (start 30.07 40.569) (end -18.93 40.569)
      (stroke (width 0.15) (type solid)) (layer "F.SilkS"))
    (fp_line (start 33.07 3.569) (end 33.07 37.569)
      (stroke (width 0.15) (type solid)) (layer "F.SilkS"))
    (fp_line (start 33.07 3.569) (end 33.07 37.569)
      (stroke (width 0.15) (type solid)) (layer "F.SilkS"))
    (fp_arc (start -21.93 3.57) (mid -21.051854 1.447853) (end -18.93 0.569)
      (stroke (width 0.15) (type solid)) (layer "F.SilkS"))
    (fp_arc (start -21.93 3.57) (mid -21.052 1.448) (end -18.93 0.57)
      (stroke (width 0.15) (type solid)) (layer "F.SilkS"))
    (fp_arc (start -18.93 40.569) (mid -21.052 39.691) (end -21.93 37.569)
      (stroke (width 0.15) (type solid)) (layer "F.SilkS"))
    (fp_arc (start -18.93 40.569) (mid -21.052 39.691) (end -21.93 37.569)
      (stroke (width 0.15) (type solid)) (layer "F.SilkS"))
    (fp_arc (start 30.07 0.569) (mid 32.190998 1.448002) (end 33.07 3.569)
      (stroke (width 0.15) (type solid)) (layer "F.SilkS"))
    (fp_arc (start 30.07 0.569) (mid 32.190998 1.448002) (end 33.07 3.569)
      (stroke (width 0.15) (type solid)) (layer "F.SilkS"))
    (fp_arc (start 33.069 37.569) (mid 32.191354 39.690647) (end 30.07 40.569)
      (stroke (width 0.15) (type solid)) (layer "F.SilkS"))
    (fp_arc (start 33.069 37.569) (mid 32.191354 39.690647) (end 30.07 40.569)
      (stroke (width 0.15) (type solid)) (layer "F.SilkS"))
  )
	(footprint "scalenode-cm4-baseboard-footprints:TP_SMD_0.75mm" (layer "F.Cu")
    (at 95.8 87.2 180)
    (property "Author" "Antmicro")
    (property "License" "Apache-2.0")
    (property "MPN" "")
    (property "Manufacturer" "")
    (property "Sheetfile" "poe.kicad_sch")
    (property "Sheetname" "PoE")
    (property "ki_description" "Test Point 0.75mm")
    (attr exclude_from_pos_files)
    (fp_text reference "TP9" (at 1 0.625 180) (layer "F.SilkS")
        (effects (font (size 0.7 0.7) (thickness 0.15)) (justify left bottom))
    )
    (fp_text value "TP_0.75mm_SMD" (at 0 1.2 180) (layer "F.Fab")
        (effects (font (size 0.7 0.7) (thickness 0.15)) (justify left bottom))
    )
    (fp_text user "License: Apache-2.0" (at -0.4 5.101 180) (layer "F.Fab") hide
        (effects (font (size 0.7 0.7) (thickness 0.15)) (justify left bottom))
    )
    (fp_text user "${REFERENCE}" (at -0.4 2.7 180) (layer "F.Fab") hide
        (effects (font (size 0.7 0.7) (thickness 0.15)) (justify left bottom))
    )
    (fp_text user "Author: Antmicro" (at -0.4 3.901 180) (layer "F.Fab") hide
        (effects (font (size 0.7 0.7) (thickness 0.15)) (justify left bottom))
    )
    (pad "1" smd circle (at 0 0 180) (size 0.75 0.75) (layers "F.Cu" "F.Mask")
      (net 272 "Net-(U3-UVLO_SEL)") (pinfunction "1") (pintype "passive"))
  )
	(footprint "scalenode-cm4-baseboard-footprints:R_0402_1005Metric" (layer "F.Cu")
    (at 92.4 87.1 90)
    (descr "Resistor SMD 0402")
    (tags "resistor SMD 0402")
    (property "Author" "Antmicro")
    (property "DNP" "DNP")
    (property "License" "Apache-2.0")
    (property "MPN" "CR0402-FX-1002GLF")
    (property "Manufacturer" "Bourns")
    (property "Sheetfile" "poe.kicad_sch")
    (property "Sheetname" "PoE")
    (property "Tolerance" "1%")
    (property "Val" "10k")
    (property "dnp" "")
    (property "exclude_from_bom" "")
    (property "ki_description" "10k resistor in 0402 package with 1% tolerance")
    (attr exclude_from_pos_files exclude_from_bom)
    (fp_text reference "R39" (at 0.95 0.4 90) (layer "F.SilkS")
        (effects (font (size 0.7 0.7) (thickness 0.15)) (justify left bottom))
    )
    (fp_text value "R_10k_0402" (at 0 1.4 90) (layer "F.Fab")
        (effects (font (size 0.7 0.7) (thickness 0.15)) (justify left bottom))
    )
    (fp_text user "License: Apache-2.0" (at -0.95 5.169 90) (layer "F.Fab") hide
        (effects (font (size 0.7 0.7) (thickness 0.15)) (justify left bottom))
    )
    (fp_text user "${REFERENCE}" (at -0.95 3.168 90) (layer "F.Fab") hide
        (effects (font (size 0.7 0.7) (thickness 0.15)) (justify left bottom))
    )
    (fp_text user "Author: Antmicro" (at -0.95 4.169 90) (layer "F.Fab") hide
        (effects (font (size 0.7 0.7) (thickness 0.15)) (justify left bottom))
    )
    (fp_rect (start -0.95 -0.48) (end 0.95 0.48)
      (stroke (width 0.05) (type solid)) (fill none) (layer "F.CrtYd"))
    (fp_rect (start -0.5 -0.25) (end 0.5 0.25)
      (stroke (width 0.15) (type solid)) (fill none) (layer "F.Fab"))
    (pad "1" smd roundrect (at -0.485 0 90) (size 0.59 0.64) (layers "F.Cu" "F.Paste" "F.Mask") (roundrect_rratio 0.25)
      (net 261 "Net-(U3-TPH)") (pintype "passive"))
    (pad "2" smd roundrect (at 0.485 0 90) (size 0.59 0.64) (layers "F.Cu" "F.Paste" "F.Mask") (roundrect_rratio 0.25)
      (net 6 "/PoE/VDD_POE_IN") (pintype "passive"))
  )
	(footprint "scalenode-cm4-baseboard-footprints:TP_SMD_0.75mm" (layer "F.Cu")
    (at 96.3 89.2)
    (property "Author" "Antmicro")
    (property "License" "Apache-2.0")
    (property "MPN" "")
    (property "Manufacturer" "")
    (property "Sheetfile" "poe.kicad_sch")
    (property "Sheetname" "PoE")
    (property "ki_description" "Test Point 0.75mm")
    (attr exclude_from_pos_files)
    (fp_text reference "TP1" (at -0.8 -0.6) (layer "F.SilkS")
        (effects (font (size 0.7 0.7) (thickness 0.15)) (justify left bottom))
    )
    (fp_text value "TP_0.75mm_SMD" (at 0 1.2) (layer "F.Fab")
        (effects (font (size 0.7 0.7) (thickness 0.15)) (justify left bottom))
    )
    (fp_text user "Author: Antmicro" (at -0.4 3.901) (layer "F.Fab") hide
        (effects (font (size 0.7 0.7) (thickness 0.15)) (justify left bottom))
    )
    (fp_text user "${REFERENCE}" (at -0.4 2.7) (layer "F.Fab") hide
        (effects (font (size 0.7 0.7) (thickness 0.15)) (justify left bottom))
    )
    (fp_text user "License: Apache-2.0" (at -0.4 5.101) (layer "F.Fab") hide
        (effects (font (size 0.7 0.7) (thickness 0.15)) (justify left bottom))
    )
    (pad "1" smd circle (at 0 0) (size 0.75 0.75) (layers "F.Cu" "F.Mask")
      (net 269 "Net-(U3-VC_IN)") (pinfunction "1") (pintype "passive"))
  )
)
